#ISCELL
  mstr_misc dns *
  *
#ISCELL
  pure_quanta quanta_title_block_c *
  *
#ISCELL
  pure_quanta_power universal_power *
  page143_i1
#ISCELL
  pure_quanta_power universal_power *
  page143_i10
#CELL
  pure_quanta q_res *
  page143_i11
#ISCELL
  pure_quanta_power gnd *
  page143_i12
#ISCELL
  pure_quanta_power gnd *
  page143_i13
#ISCELL
  pure_quanta_power universal_power *
  page143_i14
#CELL
  pure_quanta q_res *
  page143_i15
#CELL
  pure_quanta mosfet_dual_6p *
  page143_i16
#ISCELL
  pure_quanta_power universal_power *
  page143_i17
#CELL
  pure_quanta q_res *
  page143_i18
#CELL
  pure_quanta mosfet_dual_6p *
  page143_i19
#ISCELL
  pure_quanta_power universal_power *
  page143_i2
#ISCELL
  pure_quanta_power gnd *
  page143_i20
#CELL
  pure_quanta q_res *
  page143_i21
#CELL
  pure_quanta q_res *
  page143_i22
#CELL
  pure_quanta q_cap *
  page143_i24
#ISCELL
  pure_quanta_power universal_gnd *
  page143_i25
#CELL
  pure_quanta sn74lvc1g07dbvr *
  page143_i26
#ISCELL
  pure_quanta_power universal_gnd *
  page143_i27
#ISCELL
  pure_quanta_power p1v0 *
  page143_i28
#CELL
  pure_quanta q_cap *
  page143_i29
#CELL
  pure_quanta q_res *
  page143_i3
#ISCELL
  pure_quanta_power universal_gnd *
  page143_i30
#CELL
  pure_quanta sn74lvc1g07dbvr *
  page143_i31
#ISCELL
  pure_quanta_power universal_gnd *
  page143_i32
#CELL
  pure_quanta q_res *
  page143_i33
#CELL
  pure_quanta q_res *
  page143_i34
#ISCELL
  standard offpage *
  page143_i35
#ISCELL
  standard offpage *
  page143_i36
#ISCELL
  standard offpage *
  page143_i37
#CELL
  pure_quanta q_led *
  page143_i38
#ISCELL
  pure_quanta_power universal_gnd *
  page143_i39
#ISCELL
  pure_quanta_power universal_power *
  page143_i4
#ISCELL
  pure_quanta_power p1v0 *
  page143_i40
#CELL
  pure_quanta q_res *
  page143_i41
#CELL
  pure_quanta q_res *
  page143_i42
#CELL
  pure_quanta q_led *
  page143_i43
#CELL
  pure_quanta mosfet_n_gsd *
  page143_i44
#ISCELL
  pure_quanta_power p1v0 *
  page143_i45
#ISCELL
  pure_quanta_power universal_gnd *
  page143_i46
#ISCELL
  standard offpage *
  page143_i47
#ISCELL
  pure_quanta_power p1v0 *
  page143_i48
#CELL
  pure_quanta q_led *
  page143_i49
#CELL
  pure_quanta q_res *
  page143_i5
#CELL
  pure_quanta q_led *
  page143_i50
#CELL
  pure_quanta q_led *
  page143_i51
#CELL
  pure_quanta q_led *
  page143_i52
#ISCELL
  pure_quanta_power p1v0 *
  page143_i53
#CELL
  pure_quanta q_res *
  page143_i54
#CELL
  pure_quanta q_res *
  page143_i55
#CELL
  pure_quanta q_res *
  page143_i56
#CELL
  pure_quanta q_res *
  page143_i57
#CELL
  pure_quanta mosfet_dual_6p *
  page143_i58
#ISCELL
  pure_quanta_power gnd *
  page143_i6
#ISCELL
  pure_quanta_power universal_gnd *
  page143_i60
#ISCELL
  standard offpage *
  page143_i61
#CELL
  pure_quanta mosfet_dual_6p *
  page143_i62
#ISCELL
  standard offpage *
  page143_i63
#ISCELL
  pure_quanta_power universal_gnd *
  page143_i64
#ISCELL
  standard offpage *
  page143_i65
#ISCELL
  standard offpage *
  page143_i66
#ISCELL
  pure_quanta_power universal_gnd *
  page143_i67
#CELL
  pure_quanta q_led *
  page143_i68
#CELL
  pure_quanta mosfet_dual_6p *
  page143_i69
#CELL
  pure_quanta q_res *
  page143_i7
#ISCELL
  pure_quanta_power p1v0 *
  page143_i70
#CELL
  pure_quanta q_res *
  page143_i71
#CELL
  pure_quanta q_res *
  page143_i72
#CELL
  pure_quanta q_res *
  page143_i73
#CELL
  pure_quanta q_res *
  page143_i74
#CELL
  pure_quanta q_led *
  page143_i75
#CELL
  pure_quanta q_led *
  page143_i76
#CELL
  pure_quanta q_led *
  page143_i77
#ISCELL
  pure_quanta_power universal_gnd *
  page143_i78
#CELL
  pure_quanta mosfet_dual_6p *
  page143_i79
#CELL
  pure_quanta q_led *
  page143_i8
#ISCELL
  pure_quanta_power universal_gnd *
  page143_i80
#ISCELL
  standard offpage *
  page143_i81
#ISCELL
  standard offpage *
  page143_i82
#ISCELL
  standard offpage *
  page143_i83
#ISCELL
  pure_quanta_power universal_gnd *
  page143_i84
#ISCELL
  standard offpage *
  page143_i85
#CELL
  pure_quanta q_led *
  page143_i9
